(kicad_pcb
	(version 20260206)
	(generator "pcbnew")
	(generator_version "10.0")
	(general
		(thickness 1.6)
		(legacy_teardrops no)
	)
	(paper "A4")
	(title_block
		(title "v1-pdb — T6M_PDB_D_0927_0900.brd")
		(comment 1 "Open CloudServer (Microsoft) / footprints 291-300 of 321")
	)
	(layers
		(0 "F.Cu" signal "TOP")
		(4 "In1.Cu" signal "GND")
		(6 "In2.Cu" signal "IN1")
		(8 "In3.Cu" signal "VCC")
		(10 "In4.Cu" signal "VCC1")
		(12 "In5.Cu" signal "IN2")
		(14 "In6.Cu" signal "GND1")
		(2 "B.Cu" signal "BOTTOM")
		(9 "F.Adhes" user "F.Adhesive")
		(11 "B.Adhes" user "B.Adhesive")
		(13 "F.Paste" user "Package Geometry/Pastemask Top")
		(15 "B.Paste" user "Package Geometry/Pastemask Bottom")
		(5 "F.SilkS" user "Ref Des/Silkscreen Top")
		(7 "B.SilkS" user "Ref Des/Silkscreen Bottom")
		(1 "F.Mask" user "Board Geometry/Soldermask Top")
		(3 "B.Mask" user "Board Geometry/Soldermask Bottom")
		(17 "Dwgs.User" user "User.Drawings")
		(19 "Cmts.User" user "User.Comments")
		(21 "Eco1.User" user "User.Eco1")
		(23 "Eco2.User" user "User.Eco2")
		(25 "Edge.Cuts" user "Board Geometry/Outline")
		(27 "Margin" user)
		(31 "F.CrtYd" user "Package Geometry/Place Bound Top")
		(29 "B.CrtYd" user "Package Geometry/Place Bound Bottom")
		(35 "F.Fab" user "Ref Des/Assembly Top")
		(33 "B.Fab" user "Ref Des/Assembly Bottom")
	)
	(footprint ""
		(layer "F.Cu")
		(at 69.549518 -487.29138 90)
		(property "Reference" "C84"
			(at -4.090162 -0.14605 90)
			(unlocked yes)
			(layer "F.SilkS")
			(effects
				(font
					(size 0.7874 0.5842)
					(thickness 0.1524)
				)
				(justify left)
			)
		)
		(property "Value" ""
			(at 0 0 90)
			(layer "F.Fab")
			(effects
				(font
					(size 1.27 1.27)
				)
			)
		)
		(duplicate_pad_numbers_are_jumpers no)
		(fp_line
			(start 0.7874 -0.4064)
			(end 0.7874 0.4064)
			(stroke
				(width 0.1524)
				(type default)
			)
			(layer "F.SilkS")
		)
		(fp_line
			(start -0.7874 -0.4064)
			(end 0.7874 -0.4064)
			(stroke
				(width 0.1524)
				(type default)
			)
			(layer "F.SilkS")
		)
		(fp_line
			(start 0 0.381)
			(end 0 -0.381)
			(stroke
				(width 0.1524)
				(type default)
			)
			(layer "F.SilkS")
		)
		(fp_line
			(start 0.7874 0.4064)
			(end -0.7874 0.4064)
			(stroke
				(width 0.1524)
				(type default)
			)
			(layer "F.SilkS")
		)
		(fp_line
			(start -0.7874 0.4064)
			(end -0.7874 -0.4064)
			(stroke
				(width 0.1524)
				(type default)
			)
			(layer "F.SilkS")
		)
		(fp_poly
			(pts
				(xy -0.5334 0.254) (xy -0.635 0.254) (xy -0.635 0.2286) (xy -0.635 -0.254) (xy -0.5334 -0.254) (xy -0.5334 -0.2794)
				(xy 0.5334 -0.2794) (xy 0.5334 -0.254) (xy 0.635 -0.254) (xy 0.635 0.254) (xy 0.5334 0.254) (xy 0.5334 0.2794)
				(xy -0.508 0.2794) (xy -0.5334 0.2794)
			)
			(stroke
				(width 0)
				(type default)
			)
			(fill no)
			(layer "F.CrtYd")
		)
		(pad "1" smd rect
			(at 0.40005 0 90)
			(size 0.4572 0.508)
			(layers "F.Cu" "F.Mask" "F.Paste")
			(net "P12V")
		)
		(pad "2" smd rect
			(at -0.40005 0 90)
			(size 0.4572 0.508)
			(layers "F.Cu" "F.Mask" "F.Paste")
			(net "GND")
		)
	)
	(footprint ""
		(layer "F.Cu")
		(at 39.577264 -375.589546 90)
		(property "Reference" "R126"
			(at -0.735076 2.494026 0)
			(unlocked yes)
			(layer "F.SilkS")
			(effects
				(font
					(size 0.7874 0.5842)
					(thickness 0.1524)
				)
				(justify left)
			)
		)
		(property "Value" ""
			(at 0 0 90)
			(layer "F.Fab")
			(effects
				(font
					(size 1.27 1.27)
				)
			)
		)
		(duplicate_pad_numbers_are_jumpers no)
		(fp_line
			(start 0.7874 -0.4064)
			(end 0.7874 0.4064)
			(stroke
				(width 0.1524)
				(type default)
			)
			(layer "F.SilkS")
		)
		(fp_line
			(start -0.7874 -0.4064)
			(end 0.7874 -0.4064)
			(stroke
				(width 0.1524)
				(type default)
			)
			(layer "F.SilkS")
		)
		(fp_line
			(start 0.7874 0.4064)
			(end -0.7874 0.4064)
			(stroke
				(width 0.1524)
				(type default)
			)
			(layer "F.SilkS")
		)
		(fp_line
			(start -0.7874 0.4064)
			(end -0.7874 -0.4064)
			(stroke
				(width 0.1524)
				(type default)
			)
			(layer "F.SilkS")
		)
		(fp_poly
			(pts
				(xy -0.508 0.2794) (xy -0.508 0.2286) (xy -0.635 0.2286) (xy -0.635 -0.254) (xy -0.5334 -0.254)
				(xy -0.5334 -0.2794) (xy 0.5334 -0.2794) (xy 0.5334 -0.254) (xy 0.635 -0.254) (xy 0.635 0.254) (xy 0.5334 0.254)
				(xy 0.5334 0.2794)
			)
			(stroke
				(width 0)
				(type default)
			)
			(fill no)
			(layer "F.CrtYd")
		)
		(pad "1" smd rect
			(at 0.40005 0 90)
			(size 0.4572 0.508)
			(layers "F.Cu" "F.Mask" "F.Paste")
			(net "PSU5_REMOTE_P")
		)
		(pad "2" smd rect
			(at -0.40005 0 90)
			(size 0.4572 0.508)
			(layers "F.Cu" "F.Mask" "F.Paste")
			(net "PSU5_REMOTE_R2_P")
		)
	)
	(footprint ""
		(layer "F.Cu")
		(at 50.418238 -439.763154 180)
		(property "Reference" "CE20"
			(at -4.84124 2.782824 0)
			(unlocked yes)
			(layer "F.SilkS")
			(effects
				(font
					(size 0.7874 0.5842)
					(thickness 0.1524)
				)
				(justify left)
			)
		)
		(property "Value" ""
			(at 0 0 180)
			(layer "F.Fab")
			(effects
				(font
					(size 1.27 1.27)
				)
			)
		)
		(duplicate_pad_numbers_are_jumpers no)
		(fp_line
			(start 0 -4.2672)
			(end 0 4.2672)
			(stroke
				(width 0.1524)
				(type default)
			)
			(layer "F.SilkS")
		)
		(fp_circle
			(center 0 0)
			(end -4.2672 0)
			(stroke
				(width 0.1524)
				(type default)
			)
			(fill no)
			(layer "F.SilkS")
		)
		(fp_poly
			(pts
				(arc
					(start 0 -4.2672)
					(mid 4.2672 0)
					(end 0 4.2672)
				)
			)
			(stroke
				(width 0)
				(type default)
			)
			(fill yes)
			(layer "F.SilkS")
		)
		(fp_poly
			(pts
				(xy -2.5146 -0.762) (xy -0.9906 -0.762) (xy -0.9906 0.762) (xy -2.5146 0.762)
			)
			(stroke
				(width 0)
				(type default)
			)
			(fill no)
			(layer "B.CrtYd")
		)
		(fp_poly
			(pts
				(arc
					(start 1.7526 0.762)
					(mid 2.291415 -0.538815)
					(end 0.9906 0)
				)
				(arc
					(start 0.9906 0.0254)
					(mid 1.206345 0.546255)
					(end 1.7272 0.762)
				)
			)
			(stroke
				(width 0)
				(type default)
			)
			(fill no)
			(layer "B.CrtYd")
		)
		(fp_poly
			(pts
				(arc
					(start -4.2672 0)
					(mid 4.2672 0)
					(end -4.2672 0)
				)
			)
			(stroke
				(width 0)
				(type default)
			)
			(fill no)
			(layer "F.CrtYd")
		)
		(fp_circle
			(center 0 0)
			(end -4.2672 0)
			(stroke
				(width 0.1)
				(type default)
			)
			(fill no)
			(layer "F.Fab")
		)
		(fp_text user "+"
			(at -5.6642 0.15367 180)
			(unlocked yes)
			(layer "F.SilkS")
			(effects
				(font
					(size 0.7874 0.5842)
					(thickness 0.1524)
				)
				(justify left)
			)
		)
		(fp_text user "+"
			(at -5.6642 -0.34925 180)
			(unlocked yes)
			(layer "F.Fab")
			(effects
				(font
					(size 1.905 1.4224)
					(thickness 0.000001)
				)
				(justify left)
			)
		)
		(pad "1" thru_hole rect
			(at -1.75006 0 180)
			(size 1.397 1.397)
			(drill 0.9144)
			(layers "*.Cu" "*.Mask")
			(remove_unused_layers no)
			(net "P12V")
			(clearance 0.0127)
			(thermal_gap 0.0127)
			(padstack
				(mode front_inner_back)
				(layer "Inner"
					(shape circle)
					(size 1.397 1.397)
					(clearance 0.0127)
				)
				(layer "B.Cu"
					(shape rect)
					(size 1.397 1.397)
					(clearance 0.0127)
				)
			)
		)
		(pad "2" thru_hole circle
			(at 1.75006 0 180)
			(size 1.397 1.397)
			(drill 0.9144)
			(layers "*.Cu" "*.Mask")
			(remove_unused_layers no)
			(net "GND")
			(clearance 0.0127)
			(thermal_gap 0.0127)
		)
	)
	(footprint ""
		(layer "F.Cu")
		(at 39.462964 -21.994368 90)
		(property "Reference" "R110"
			(at -0.675132 1.446022 0)
			(unlocked yes)
			(layer "F.SilkS")
			(effects
				(font
					(size 0.7874 0.5842)
					(thickness 0.1524)
				)
				(justify left)
			)
		)
		(property "Value" ""
			(at 0 0 90)
			(layer "F.Fab")
			(effects
				(font
					(size 1.27 1.27)
				)
			)
		)
		(duplicate_pad_numbers_are_jumpers no)
		(fp_line
			(start 0.7874 -0.4064)
			(end 0.7874 0.4064)
			(stroke
				(width 0.1524)
				(type default)
			)
			(layer "F.SilkS")
		)
		(fp_line
			(start -0.7874 -0.4064)
			(end 0.7874 -0.4064)
			(stroke
				(width 0.1524)
				(type default)
			)
			(layer "F.SilkS")
		)
		(fp_line
			(start 0.7874 0.4064)
			(end -0.7874 0.4064)
			(stroke
				(width 0.1524)
				(type default)
			)
			(layer "F.SilkS")
		)
		(fp_line
			(start -0.7874 0.4064)
			(end -0.7874 -0.4064)
			(stroke
				(width 0.1524)
				(type default)
			)
			(layer "F.SilkS")
		)
		(fp_poly
			(pts
				(xy -0.508 0.2794) (xy -0.508 0.2286) (xy -0.635 0.2286) (xy -0.635 -0.254) (xy -0.5334 -0.254)
				(xy -0.5334 -0.2794) (xy 0.5334 -0.2794) (xy 0.5334 -0.254) (xy 0.635 -0.254) (xy 0.635 0.254) (xy 0.5334 0.254)
				(xy 0.5334 0.2794)
			)
			(stroke
				(width 0)
				(type default)
			)
			(fill no)
			(layer "F.CrtYd")
		)
		(pad "1" smd rect
			(at 0.40005 0 90)
			(size 0.4572 0.508)
			(layers "F.Cu" "F.Mask" "F.Paste")
			(net "PSU1_REMOTE_P")
		)
		(pad "2" smd rect
			(at -0.40005 0 90)
			(size 0.4572 0.508)
			(layers "F.Cu" "F.Mask" "F.Paste")
			(net "PSU1_REMOTE_R2_P")
		)
	)
	(footprint ""
		(layer "F.Cu")
		(at 25.931622 -96.872044)
		(property "Reference" "R68"
			(at -4.080256 -0.075692 0)
			(unlocked yes)
			(layer "F.SilkS")
			(effects
				(font
					(size 0.7874 0.5842)
					(thickness 0.1524)
				)
				(justify left)
			)
		)
		(property "Value" ""
			(at 0 0 0)
			(layer "F.Fab")
			(effects
				(font
					(size 1.27 1.27)
				)
			)
		)
		(duplicate_pad_numbers_are_jumpers no)
		(fp_line
			(start -0.7874 -0.4064)
			(end 0.7874 -0.4064)
			(stroke
				(width 0.1524)
				(type default)
			)
			(layer "F.SilkS")
		)
		(fp_line
			(start -0.7874 0.4064)
			(end -0.7874 -0.4064)
			(stroke
				(width 0.1524)
				(type default)
			)
			(layer "F.SilkS")
		)
		(fp_line
			(start 0.7874 -0.4064)
			(end 0.7874 0.4064)
			(stroke
				(width 0.1524)
				(type default)
			)
			(layer "F.SilkS")
		)
		(fp_line
			(start 0.7874 0.4064)
			(end -0.7874 0.4064)
			(stroke
				(width 0.1524)
				(type default)
			)
			(layer "F.SilkS")
		)
		(fp_poly
			(pts
				(xy -0.508 0.2794) (xy -0.508 0.2286) (xy -0.635 0.2286) (xy -0.635 -0.254) (xy -0.5334 -0.254)
				(xy -0.5334 -0.2794) (xy 0.5334 -0.2794) (xy 0.5334 -0.254) (xy 0.635 -0.254) (xy 0.635 0.254) (xy 0.5334 0.254)
				(xy 0.5334 0.2794)
			)
			(stroke
				(width 0)
				(type default)
			)
			(fill no)
			(layer "F.CrtYd")
		)
		(pad "1" smd rect
			(at 0.40005 0)
			(size 0.4572 0.508)
			(layers "F.Cu" "F.Mask" "F.Paste")
			(net "PSU2_RESET")
		)
		(pad "2" smd rect
			(at -0.40005 0)
			(size 0.4572 0.508)
			(layers "F.Cu" "F.Mask" "F.Paste")
			(net "P12V_STBY")
		)
	)
	(footprint ""
		(layer "F.Cu")
		(at 39.581836 -376.389646 -90)
		(property "Reference" "R102"
			(at -1.34493 0.095758 90)
			(unlocked yes)
			(layer "F.SilkS")
			(effects
				(font
					(size 0.7874 0.5842)
					(thickness 0.1524)
				)
				(justify left)
			)
		)
		(property "Value" ""
			(at 0 0 270)
			(layer "F.Fab")
			(effects
				(font
					(size 1.27 1.27)
				)
			)
		)
		(duplicate_pad_numbers_are_jumpers no)
		(fp_line
			(start -0.7874 0.4064)
			(end -0.7874 -0.4064)
			(stroke
				(width 0.1524)
				(type default)
			)
			(layer "F.SilkS")
		)
		(fp_line
			(start 0.7874 0.4064)
			(end -0.7874 0.4064)
			(stroke
				(width 0.1524)
				(type default)
			)
			(layer "F.SilkS")
		)
		(fp_line
			(start -0.7874 -0.4064)
			(end 0.7874 -0.4064)
			(stroke
				(width 0.1524)
				(type default)
			)
			(layer "F.SilkS")
		)
		(fp_line
			(start 0.7874 -0.4064)
			(end 0.7874 0.4064)
			(stroke
				(width 0.1524)
				(type default)
			)
			(layer "F.SilkS")
		)
		(fp_poly
			(pts
				(xy -0.508 0.2794) (xy -0.508 0.2286) (xy -0.635 0.2286) (xy -0.635 -0.254) (xy -0.5334 -0.254)
				(xy -0.5334 -0.2794) (xy 0.5334 -0.2794) (xy 0.5334 -0.254) (xy 0.635 -0.254) (xy 0.635 0.254) (xy 0.5334 0.254)
				(xy 0.5334 0.2794)
			)
			(stroke
				(width 0)
				(type default)
			)
			(fill no)
			(layer "F.CrtYd")
		)
		(pad "1" smd rect
			(at 0.40005 0 270)
			(size 0.4572 0.508)
			(layers "F.Cu" "F.Mask" "F.Paste")
			(net "PSU5_REMOTE_P")
		)
		(pad "2" smd rect
			(at -0.40005 0 270)
			(size 0.4572 0.508)
			(layers "F.Cu" "F.Mask" "F.Paste")
			(net "PSU5_REMOTE_R_P")
		)
	)
	(footprint ""
		(layer "F.Cu")
		(at 50.478944 -196.729604 180)
		(property "Reference" "CE10"
			(at -4.974844 0.065278 0)
			(unlocked yes)
			(layer "F.SilkS")
			(effects
				(font
					(size 0.7874 0.5842)
					(thickness 0.1524)
				)
				(justify left)
			)
		)
		(property "Value" ""
			(at 0 0 180)
			(layer "F.Fab")
			(effects
				(font
					(size 1.27 1.27)
				)
			)
		)
		(duplicate_pad_numbers_are_jumpers no)
		(fp_line
			(start 0 -4.2672)
			(end 0 4.2672)
			(stroke
				(width 0.1524)
				(type default)
			)
			(layer "F.SilkS")
		)
		(fp_circle
			(center 0 0)
			(end -4.2672 0)
			(stroke
				(width 0.1524)
				(type default)
			)
			(fill no)
			(layer "F.SilkS")
		)
		(fp_poly
			(pts
				(arc
					(start 0 -4.2672)
					(mid 4.2672 0)
					(end 0 4.2672)
				)
			)
			(stroke
				(width 0)
				(type default)
			)
			(fill yes)
			(layer "F.SilkS")
		)
		(fp_poly
			(pts
				(xy -2.5146 -0.762) (xy -0.9906 -0.762) (xy -0.9906 0.762) (xy -2.5146 0.762)
			)
			(stroke
				(width 0)
				(type default)
			)
			(fill no)
			(layer "B.CrtYd")
		)
		(fp_poly
			(pts
				(arc
					(start 1.7526 0.762)
					(mid 2.291415 -0.538815)
					(end 0.9906 0)
				)
				(arc
					(start 0.9906 0.0254)
					(mid 1.206345 0.546255)
					(end 1.7272 0.762)
				)
			)
			(stroke
				(width 0)
				(type default)
			)
			(fill no)
			(layer "B.CrtYd")
		)
		(fp_poly
			(pts
				(arc
					(start -4.2672 0)
					(mid 4.2672 0)
					(end -4.2672 0)
				)
			)
			(stroke
				(width 0)
				(type default)
			)
			(fill no)
			(layer "F.CrtYd")
		)
		(fp_circle
			(center 0 0)
			(end -4.2672 0)
			(stroke
				(width 0.1)
				(type default)
			)
			(fill no)
			(layer "F.Fab")
		)
		(fp_text user "+"
			(at -5.846572 -1.215136 180)
			(unlocked yes)
			(layer "F.SilkS")
			(effects
				(font
					(size 0.7874 0.5842)
					(thickness 0.1524)
				)
				(justify left)
			)
		)
		(fp_text user "+"
			(at -5.6642 -0.34925 180)
			(unlocked yes)
			(layer "F.Fab")
			(effects
				(font
					(size 1.905 1.4224)
					(thickness 0.000001)
				)
				(justify left)
			)
		)
		(pad "1" thru_hole rect
			(at -1.75006 0 180)
			(size 1.397 1.397)
			(drill 0.9144)
			(layers "*.Cu" "*.Mask")
			(remove_unused_layers no)
			(net "P12V")
			(clearance 0.0127)
			(thermal_gap 0.0127)
			(padstack
				(mode front_inner_back)
				(layer "Inner"
					(shape circle)
					(size 1.397 1.397)
					(clearance 0.0127)
				)
				(layer "B.Cu"
					(shape rect)
					(size 1.397 1.397)
					(clearance 0.0127)
				)
			)
		)
		(pad "2" thru_hole circle
			(at 1.75006 0 180)
			(size 1.397 1.397)
			(drill 0.9144)
			(layers "*.Cu" "*.Mask")
			(remove_unused_layers no)
			(net "GND")
			(clearance 0.0127)
			(thermal_gap 0.0127)
		)
	)
	(footprint ""
		(layer "F.Cu")
		(at 14.9225 -146.162014 -90)
		(property "Reference" "R148"
			(at 1.076452 1.187704 90)
			(unlocked yes)
			(layer "F.SilkS")
			(effects
				(font
					(size 0.7874 0.5842)
					(thickness 0.1524)
				)
				(justify left)
			)
		)
		(property "Value" ""
			(at 0 0 270)
			(layer "F.Fab")
			(effects
				(font
					(size 1.27 1.27)
				)
			)
		)
		(duplicate_pad_numbers_are_jumpers no)
		(fp_line
			(start -0.7874 0.4064)
			(end -0.7874 -0.4064)
			(stroke
				(width 0.1524)
				(type default)
			)
			(layer "F.SilkS")
		)
		(fp_line
			(start 0.7874 0.4064)
			(end -0.7874 0.4064)
			(stroke
				(width 0.1524)
				(type default)
			)
			(layer "F.SilkS")
		)
		(fp_line
			(start -0.7874 -0.4064)
			(end 0.7874 -0.4064)
			(stroke
				(width 0.1524)
				(type default)
			)
			(layer "F.SilkS")
		)
		(fp_line
			(start 0.7874 -0.4064)
			(end 0.7874 0.4064)
			(stroke
				(width 0.1524)
				(type default)
			)
			(layer "F.SilkS")
		)
		(fp_poly
			(pts
				(xy -0.508 0.2794) (xy -0.508 0.2286) (xy -0.635 0.2286) (xy -0.635 -0.254) (xy -0.5334 -0.254)
				(xy -0.5334 -0.2794) (xy 0.5334 -0.2794) (xy 0.5334 -0.254) (xy 0.635 -0.254) (xy 0.635 0.254) (xy 0.5334 0.254)
				(xy 0.5334 0.2794)
			)
			(stroke
				(width 0)
				(type default)
			)
			(fill no)
			(layer "F.CrtYd")
		)
		(pad "1" smd rect
			(at 0.40005 0 270)
			(size 0.4572 0.508)
			(layers "F.Cu" "F.Mask" "F.Paste")
			(net "N42126673")
		)
		(pad "2" smd rect
			(at -0.40005 0 270)
			(size 0.4572 0.508)
			(layers "F.Cu" "F.Mask" "F.Paste")
			(net "GND")
		)
	)
	(footprint ""
		(layer "F.Cu")
		(at 27.640026 -284.62986 90)
		(property "Reference" "R125"
			(at -3.83413 -1.65354 90)
			(unlocked yes)
			(layer "F.SilkS")
			(effects
				(font
					(size 0.7874 0.5842)
					(thickness 0.1524)
				)
				(justify left)
			)
		)
		(property "Value" ""
			(at 0 0 90)
			(layer "F.Fab")
			(effects
				(font
					(size 1.27 1.27)
				)
			)
		)
		(duplicate_pad_numbers_are_jumpers no)
		(fp_line
			(start 0.7874 -0.4064)
			(end 0.7874 0.4064)
			(stroke
				(width 0.1524)
				(type default)
			)
			(layer "F.SilkS")
		)
		(fp_line
			(start -0.7874 -0.4064)
			(end 0.7874 -0.4064)
			(stroke
				(width 0.1524)
				(type default)
			)
			(layer "F.SilkS")
		)
		(fp_line
			(start 0.7874 0.4064)
			(end -0.7874 0.4064)
			(stroke
				(width 0.1524)
				(type default)
			)
			(layer "F.SilkS")
		)
		(fp_line
			(start -0.7874 0.4064)
			(end -0.7874 -0.4064)
			(stroke
				(width 0.1524)
				(type default)
			)
			(layer "F.SilkS")
		)
		(fp_poly
			(pts
				(xy -0.508 0.2794) (xy -0.508 0.2286) (xy -0.635 0.2286) (xy -0.635 -0.254) (xy -0.5334 -0.254)
				(xy -0.5334 -0.2794) (xy 0.5334 -0.2794) (xy 0.5334 -0.254) (xy 0.635 -0.254) (xy 0.635 0.254) (xy 0.5334 0.254)
				(xy 0.5334 0.2794)
			)
			(stroke
				(width 0)
				(type default)
			)
			(fill no)
			(layer "F.CrtYd")
		)
		(pad "1" smd rect
			(at 0.40005 0 90)
			(size 0.4572 0.508)
			(layers "F.Cu" "F.Mask" "F.Paste")
			(net "PSU4_REMOTE_N")
		)
		(pad "2" smd rect
			(at -0.40005 0 90)
			(size 0.4572 0.508)
			(layers "F.Cu" "F.Mask" "F.Paste")
			(net "PSU4_REMOTE_R2_N")
		)
	)
	(footprint ""
		(layer "F.Cu")
		(at 27.052778 -10.617962)
		(property "Reference" "R50"
			(at -4.020312 -0.32258 0)
			(unlocked yes)
			(layer "F.SilkS")
			(effects
				(font
					(size 0.7874 0.5842)
					(thickness 0.1524)
				)
				(justify left)
			)
		)
		(property "Value" ""
			(at 0 0 0)
			(layer "F.Fab")
			(effects
				(font
					(size 1.27 1.27)
				)
			)
		)
		(duplicate_pad_numbers_are_jumpers no)
		(fp_line
			(start -0.7874 -0.4064)
			(end 0.7874 -0.4064)
			(stroke
				(width 0.1524)
				(type default)
			)
			(layer "F.SilkS")
		)
		(fp_line
			(start -0.7874 0.4064)
			(end -0.7874 -0.4064)
			(stroke
				(width 0.1524)
				(type default)
			)
			(layer "F.SilkS")
		)
		(fp_line
			(start 0.7874 -0.4064)
			(end 0.7874 0.4064)
			(stroke
				(width 0.1524)
				(type default)
			)
			(layer "F.SilkS")
		)
		(fp_line
			(start 0.7874 0.4064)
			(end -0.7874 0.4064)
			(stroke
				(width 0.1524)
				(type default)
			)
			(layer "F.SilkS")
		)
		(fp_poly
			(pts
				(xy -0.508 0.2794) (xy -0.508 0.2286) (xy -0.635 0.2286) (xy -0.635 -0.254) (xy -0.5334 -0.254)
				(xy -0.5334 -0.2794) (xy 0.5334 -0.2794) (xy 0.5334 -0.254) (xy 0.635 -0.254) (xy 0.635 0.254) (xy 0.5334 0.254)
				(xy 0.5334 0.2794)
			)
			(stroke
				(width 0)
				(type default)
			)
			(fill no)
			(layer "F.CrtYd")
		)
		(pad "1" smd rect
			(at 0.40005 0)
			(size 0.4572 0.508)
			(layers "F.Cu" "F.Mask" "F.Paste")
			(net "GND")
		)
		(pad "2" smd rect
			(at -0.40005 0)
			(size 0.4572 0.508)
			(layers "F.Cu" "F.Mask" "F.Paste")
			(net "PSU2_PS_ON_N")
		)
	)
)
